FILE_TYPE = MACRO_DRAWING;
SET COLOR_WIRE YELLOW;
SET COLOR_PROP MONO;
SET COLOR_DOT WHITE;
SET COLOR_ARC YELLOW;
SET COLOR_BODY GREEN;
SET COLOR_NOTE MONO;
SET PROP_DISPLAY VALUE;
SET PAGE_NUMBER P18;
FORCEADD INTEL_CORP_BPAGE..1
(0 0);
FORCEPROP 1 LAST CDS_CON_LAST_MODIFIED Fri Jun 16 17:48:03 2017
J 0
(-1425 325);
PAINT ORANGE (-1425 325);
DISPLAY INVISIBLE (-1425 325);
FORCEPROP 2 LAST CUSTOM_TXT_CDS <XR_PAGE_TITLE>
J 0
(-7890 5250);
DISPLAY 0.638298 (-7890 5250);
PAINT PINK (-7890 5250);
DISPLAY INVISIBLE (-7890 5250);
FORCEPROP 2 LAST CUSTOM_TXT_CDS <CON_LAST_MODIFIED>
J 0
(-4000 100);
PAINT ORANGE (-4000 100);
FORCEPROP 2 LAST CUSTOM_TXT_CDS <CURRENT_DESIGN_SHEET> OF <TOTAL_DESIGN_SHEETS>
J 0
(-500 25);
PAINT ORANGE (-500 25);
FORCEPROP 1 LAST SCH_TITLE FAST_PROCHOT BLOCK DIAGRAM
J 0
(-7950 50);
DISPLAY 1.212766 (-7950 50);
PAINT ORANGE (-7950 50);
FORCEPROP 1 LAST COMMENT_BODY TRUE
J 0
(12 12);
DISPLAY 0.468085 (12 12);
PAINT GREEN (12 12);
DISPLAY INVISIBLE (12 12);
FORCEPROP 2 LAST CDS_LIB mstr_symbols
J 0
(0 0);
PAINT MONO (0 0);
DISPLAY INVISIBLE (0 0);
FORCEPROP 2 LAST PAGE_BORDER TRUE
J 0
(-7890 5250);
DISPLAY 0.638298 (-7890 5250);
PAINT PINK (-7890 5250);
DISPLAY INVISIBLE (-7890 5250);
FORCEPROP 2 LAST CDS_XR_PAGE_TITLE CR-18 : @BASEBOARD_FAB2_LIB.BASEBOARD_FAB2(SCH_1):PAGE18
J 0
(-7890 5250);
DISPLAY 0.638298 (-7890 5250);
PAINT PINK (-7890 5250);
DISPLAY INVISIBLE (-7890 5250);
FORCENOTE
$CDS_IMAGE|TiogaPass_SYSTEM_Block_diagram_9_0411.jpg|5500|5500
(-4100 2450) 0;
DISPLAY LEFT (-4100 2450);
QUIT
